(kicad_pcb
	(version 20260206)
	(generator "pcbnew")
	(generator_version "10.0")
	(general
		(thickness 1.6)
		(legacy_teardrops no)
	)
	(paper "A4")
	(title_block
		(title "01162023_DA0F0TEBIF0_F0T_Expander_BD_F_brd_V02_OCP.brd")
		(comment 1 "Grand Teton / footprints 8527-8536 of 9728")
	)
	(layers
		(0 "F.Cu" signal "TOP")
		(4 "In1.Cu" signal "GND")
		(6 "In2.Cu" signal "VCC")
		(8 "In3.Cu" signal "VCC1")
		(10 "In4.Cu" signal "GND1")
		(12 "In5.Cu" signal "IN1")
		(14 "In6.Cu" signal "GND2")
		(16 "In7.Cu" signal "IN2")
		(18 "In8.Cu" signal "GND3")
		(20 "In9.Cu" signal "IN3")
		(22 "In10.Cu" signal "GND4")
		(24 "In11.Cu" signal "IN4")
		(26 "In12.Cu" signal "GND5")
		(28 "In13.Cu" signal "IN5")
		(30 "In14.Cu" signal "GND6")
		(32 "In15.Cu" signal "IN6")
		(34 "In16.Cu" signal "GND7")
		(2 "B.Cu" signal "BOTTOM")
		(9 "F.Adhes" user "F.Adhesive")
		(11 "B.Adhes" user "B.Adhesive")
		(13 "F.Paste" user "Package Geometry/Pastemask Top")
		(15 "B.Paste" user "Package Geometry/Pastemask Bottom")
		(5 "F.SilkS" user "Ref Des/Silkscreen Top")
		(7 "B.SilkS" user "Ref Des/Silkscreen Bottom")
		(1 "F.Mask" user "Board Geometry/Soldermask Top")
		(3 "B.Mask" user "Board Geometry/Soldermask Bottom")
		(17 "Dwgs.User" user "User.Drawings")
		(19 "Cmts.User" user "User.Comments")
		(21 "Eco1.User" user "User.Eco1")
		(23 "Eco2.User" user "User.Eco2")
		(25 "Edge.Cuts" user "Board Geometry/Outline")
		(27 "Margin" user)
		(31 "F.CrtYd" user "Package Geometry/Place Bound Top")
		(29 "B.CrtYd" user "Package Geometry/Place Bound Bottom")
		(35 "F.Fab" user "Ref Des/Assembly Top")
		(33 "B.Fab" user "Ref Des/Assembly Bottom")
	)
	(footprint ""
		(layer "B.Cu")
		(at 111.25327 -308.580028 90)
		(property "Reference" "C4194"
			(at 0 0 90)
			(layer "B.SilkS")
			(hide yes)
			(effects
				(font
					(size 1.27 1.27)
				)
				(justify mirror)
			)
		)
		(property "Value" ""
			(at 0 0 90)
			(layer "B.Fab")
			(effects
				(font
					(size 1.27 1.27)
				)
				(justify mirror)
			)
		)
		(duplicate_pad_numbers_are_jumpers no)
		(fp_line
			(start 1.2954 -0.5842)
			(end -1.2954 -0.5842)
			(stroke
				(width 0.1524)
				(type default)
			)
			(layer "B.SilkS")
		)
		(fp_line
			(start -1.2954 -0.5842)
			(end -1.2954 0.5842)
			(stroke
				(width 0.1524)
				(type default)
			)
			(layer "B.SilkS")
		)
		(fp_line
			(start 1.2954 0.5842)
			(end 1.2954 -0.5842)
			(stroke
				(width 0.1524)
				(type default)
			)
			(layer "B.SilkS")
		)
		(fp_line
			(start -1.2954 0.5842)
			(end 1.2954 0.5842)
			(stroke
				(width 0.1524)
				(type default)
			)
			(layer "B.SilkS")
		)
		(fp_line
			(start 0.8636 -0.4572)
			(end -0.8636 -0.4572)
			(stroke
				(width 0.1)
				(type default)
			)
			(layer "B.Fab")
		)
		(fp_line
			(start -0.8636 -0.4572)
			(end -0.8636 -0.4064)
			(stroke
				(width 0.1)
				(type default)
			)
			(layer "B.Fab")
		)
		(fp_line
			(start 1.1938 -0.4064)
			(end 0.8636 -0.4064)
			(stroke
				(width 0.1)
				(type default)
			)
			(layer "B.Fab")
		)
		(fp_line
			(start 0.8636 -0.4064)
			(end 0.8636 -0.4572)
			(stroke
				(width 0.1)
				(type default)
			)
			(layer "B.Fab")
		)
		(fp_line
			(start -0.8636 -0.4064)
			(end -1.1938 -0.4064)
			(stroke
				(width 0.1)
				(type default)
			)
			(layer "B.Fab")
		)
		(fp_line
			(start -1.1938 -0.4064)
			(end -1.1938 0.4064)
			(stroke
				(width 0.1)
				(type default)
			)
			(layer "B.Fab")
		)
		(fp_line
			(start 1.1938 0.4064)
			(end 1.1938 -0.4064)
			(stroke
				(width 0.1)
				(type default)
			)
			(layer "B.Fab")
		)
		(fp_line
			(start 0.8636 0.4064)
			(end 1.1938 0.4064)
			(stroke
				(width 0.1)
				(type default)
			)
			(layer "B.Fab")
		)
		(fp_line
			(start -0.8636 0.4064)
			(end -0.8636 0.4572)
			(stroke
				(width 0.1)
				(type default)
			)
			(layer "B.Fab")
		)
		(fp_line
			(start -1.1938 0.4064)
			(end -0.8636 0.4064)
			(stroke
				(width 0.1)
				(type default)
			)
			(layer "B.Fab")
		)
		(fp_line
			(start 0.8636 0.4572)
			(end 0.8636 0.4064)
			(stroke
				(width 0.1)
				(type default)
			)
			(layer "B.Fab")
		)
		(fp_line
			(start -0.8636 0.4572)
			(end 0.8636 0.4572)
			(stroke
				(width 0.1)
				(type default)
			)
			(layer "B.Fab")
		)
		(pad "1" smd rect
			(at 0.7366 0)
			(size 0.7112 0.8128)
			(layers "B.Cu" "B.Mask" "B.Paste")
			(net "P0V8_PEX0")
		)
		(pad "2" smd rect
			(at -0.7366 0)
			(size 0.7112 0.8128)
			(layers "B.Cu" "B.Mask" "B.Paste")
			(net "GND")
		)
	)
	(footprint ""
		(layer "B.Cu")
		(at 166.725092 -305.399948 -90)
		(property "Reference" "C3141"
			(at 0 0 90)
			(layer "B.SilkS")
			(hide yes)
			(effects
				(font
					(size 1.27 1.27)
				)
				(justify mirror)
			)
		)
		(property "Value" ""
			(at 0 0 90)
			(layer "B.Fab")
			(effects
				(font
					(size 1.27 1.27)
				)
				(justify mirror)
			)
		)
		(duplicate_pad_numbers_are_jumpers no)
		(fp_line
			(start -0.299974 0.150114)
			(end 0.299974 0.150114)
			(stroke
				(width 0.1)
				(type default)
			)
			(layer "B.Fab")
		)
		(fp_line
			(start 0.299974 0.150114)
			(end 0.299974 -0.150114)
			(stroke
				(width 0.1)
				(type default)
			)
			(layer "B.Fab")
		)
		(fp_line
			(start -0.299974 -0.150114)
			(end -0.299974 0.150114)
			(stroke
				(width 0.1)
				(type default)
			)
			(layer "B.Fab")
		)
		(fp_line
			(start 0.299974 -0.150114)
			(end -0.299974 -0.150114)
			(stroke
				(width 0.1)
				(type default)
			)
			(layer "B.Fab")
		)
		(pad "1" smd rect
			(at 0.2667 0 90)
			(size 0.3048 0.381)
			(layers "B.Cu" "B.Mask" "B.Paste")
			(net "P1V25_SERDES_VDDPLL_PEX1")
		)
		(pad "2" smd rect
			(at -0.2667 0 90)
			(size 0.3048 0.381)
			(layers "B.Cu" "B.Mask" "B.Paste")
			(net "GND")
		)
	)
	(footprint ""
		(layer "B.Cu")
		(at 251.18568 -83.935316 90)
		(property "Reference" "L9"
			(at 0 0 90)
			(layer "B.SilkS")
			(hide yes)
			(effects
				(font
					(size 1.27 1.27)
				)
				(justify mirror)
			)
		)
		(property "Value" ""
			(at 0 0 90)
			(layer "B.Fab")
			(effects
				(font
					(size 1.27 1.27)
				)
				(justify mirror)
			)
		)
		(duplicate_pad_numbers_are_jumpers no)
		(fp_line
			(start 1.63576 -0.8128)
			(end -1.63576 -0.8128)
			(stroke
				(width 0.1524)
				(type default)
			)
			(layer "B.SilkS")
		)
		(fp_line
			(start 1.63576 -0.8128)
			(end 1.63576 0.8128)
			(stroke
				(width 0.1524)
				(type default)
			)
			(layer "B.SilkS")
		)
		(fp_line
			(start -1.63576 -0.8128)
			(end -1.63576 0.8128)
			(stroke
				(width 0.1524)
				(type default)
			)
			(layer "B.SilkS")
		)
		(fp_line
			(start -1.63576 0.8128)
			(end 1.63576 0.8128)
			(stroke
				(width 0.1524)
				(type default)
			)
			(layer "B.SilkS")
		)
		(fp_line
			(start 1.56083 -0.738632)
			(end 1.56083 0.7366)
			(stroke
				(width 0.1)
				(type default)
			)
			(layer "B.Fab")
		)
		(fp_line
			(start -1.560576 -0.738632)
			(end 1.56083 -0.738632)
			(stroke
				(width 0.1)
				(type default)
			)
			(layer "B.Fab")
		)
		(fp_line
			(start 1.56083 0.7366)
			(end 1.524 0.7366)
			(stroke
				(width 0.1)
				(type default)
			)
			(layer "B.Fab")
		)
		(fp_line
			(start 1.524 0.7366)
			(end -1.524 0.7366)
			(stroke
				(width 0.1)
				(type default)
			)
			(layer "B.Fab")
		)
		(fp_line
			(start -1.524 0.7366)
			(end -1.560576 0.7366)
			(stroke
				(width 0.1)
				(type default)
			)
			(layer "B.Fab")
		)
		(fp_line
			(start -1.560576 0.7366)
			(end -1.560576 -0.738632)
			(stroke
				(width 0.1)
				(type default)
			)
			(layer "B.Fab")
		)
		(pad "1" smd rect
			(at 0.94996 0 90)
			(size 1.1176 1.3716)
			(layers "B.Cu" "B.Mask" "B.Paste")
			(net "P3V3")
		)
		(pad "2" smd rect
			(at -0.94996 0 90)
			(size 1.1176 1.3716)
			(layers "B.Cu" "B.Mask" "B.Paste")
			(net "P3V3_CLK_GEN_VDDXTAL_CK440")
		)
	)
	(footprint ""
		(layer "B.Cu")
		(at 288.524696 -286.399732 90)
		(property "Reference" "C3309"
			(at 0 0 90)
			(layer "B.SilkS")
			(hide yes)
			(effects
				(font
					(size 1.27 1.27)
				)
				(justify mirror)
			)
		)
		(property "Value" ""
			(at 0 0 90)
			(layer "B.Fab")
			(effects
				(font
					(size 1.27 1.27)
				)
				(justify mirror)
			)
		)
		(duplicate_pad_numbers_are_jumpers no)
		(fp_line
			(start 0.299974 -0.150114)
			(end -0.299974 -0.150114)
			(stroke
				(width 0.1)
				(type default)
			)
			(layer "B.Fab")
		)
		(fp_line
			(start -0.299974 -0.150114)
			(end -0.299974 0.150114)
			(stroke
				(width 0.1)
				(type default)
			)
			(layer "B.Fab")
		)
		(fp_line
			(start 0.299974 0.150114)
			(end 0.299974 -0.150114)
			(stroke
				(width 0.1)
				(type default)
			)
			(layer "B.Fab")
		)
		(fp_line
			(start -0.299974 0.150114)
			(end 0.299974 0.150114)
			(stroke
				(width 0.1)
				(type default)
			)
			(layer "B.Fab")
		)
		(pad "1" smd rect
			(at 0.2667 0 270)
			(size 0.3048 0.381)
			(layers "B.Cu" "B.Mask" "B.Paste")
			(net "P1V25_SERDES_VDDPLL_PEX2")
		)
		(pad "2" smd rect
			(at -0.2667 0 270)
			(size 0.3048 0.381)
			(layers "B.Cu" "B.Mask" "B.Paste")
			(net "GND")
		)
	)
	(footprint ""
		(layer "B.Cu")
		(at 230.450644 -231.225598 90)
		(property "Reference" "R4543"
			(at 0 0 90)
			(layer "B.SilkS")
			(hide yes)
			(effects
				(font
					(size 1.27 1.27)
				)
				(justify mirror)
			)
		)
		(property "Value" ""
			(at 0 0 90)
			(layer "B.Fab")
			(effects
				(font
					(size 1.27 1.27)
				)
				(justify mirror)
			)
		)
		(duplicate_pad_numbers_are_jumpers no)
		(fp_line
			(start 0.7874 -0.4064)
			(end -0.7874 -0.4064)
			(stroke
				(width 0.1524)
				(type default)
			)
			(layer "B.SilkS")
		)
		(fp_line
			(start -0.7874 -0.4064)
			(end -0.7874 0.4064)
			(stroke
				(width 0.1524)
				(type default)
			)
			(layer "B.SilkS")
		)
		(fp_line
			(start 0.7874 0.4064)
			(end 0.7874 -0.4064)
			(stroke
				(width 0.1524)
				(type default)
			)
			(layer "B.SilkS")
		)
		(fp_line
			(start -0.7874 0.4064)
			(end 0.7874 0.4064)
			(stroke
				(width 0.1524)
				(type default)
			)
			(layer "B.SilkS")
		)
		(fp_line
			(start 0.67945 -0.305054)
			(end 0.12065 -0.305054)
			(stroke
				(width 0.1)
				(type default)
			)
			(layer "B.Fab")
		)
		(fp_line
			(start 0.12065 -0.305054)
			(end 0.12065 -0.2794)
			(stroke
				(width 0.1)
				(type default)
			)
			(layer "B.Fab")
		)
		(fp_line
			(start -0.12065 -0.3048)
			(end -0.67945 -0.3048)
			(stroke
				(width 0.1)
				(type default)
			)
			(layer "B.Fab")
		)
		(fp_line
			(start -0.67945 -0.3048)
			(end -0.67945 0.3048)
			(stroke
				(width 0.1)
				(type default)
			)
			(layer "B.Fab")
		)
		(fp_line
			(start 0.12065 -0.2794)
			(end -0.12065 -0.2794)
			(stroke
				(width 0.1)
				(type default)
			)
			(layer "B.Fab")
		)
		(fp_line
			(start -0.12065 -0.2794)
			(end -0.12065 -0.3048)
			(stroke
				(width 0.1)
				(type default)
			)
			(layer "B.Fab")
		)
		(fp_line
			(start 0.12065 0.2794)
			(end 0.12065 0.3048)
			(stroke
				(width 0.1)
				(type default)
			)
			(layer "B.Fab")
		)
		(fp_line
			(start -0.120396 0.2794)
			(end 0.12065 0.2794)
			(stroke
				(width 0.1)
				(type default)
			)
			(layer "B.Fab")
		)
		(fp_line
			(start 0.67945 0.3048)
			(end 0.67945 -0.305054)
			(stroke
				(width 0.1)
				(type default)
			)
			(layer "B.Fab")
		)
		(fp_line
			(start 0.12065 0.3048)
			(end 0.67945 0.3048)
			(stroke
				(width 0.1)
				(type default)
			)
			(layer "B.Fab")
		)
		(fp_line
			(start -0.120396 0.3048)
			(end -0.120396 0.2794)
			(stroke
				(width 0.1)
				(type default)
			)
			(layer "B.Fab")
		)
		(fp_line
			(start -0.67945 0.3048)
			(end -0.120396 0.3048)
			(stroke
				(width 0.1)
				(type default)
			)
			(layer "B.Fab")
		)
		(pad "1" smd circle
			(at 0.40005 0 270)
			(size 0 0)
			(layers "B.Cu" "B.Mask" "B.Paste")
			(net "NIC7_MAIN_PWR_BIC_EN_R")
		)
		(pad "2" smd circle
			(at -0.40005 0 270)
			(size 0 0)
			(layers "B.Cu" "B.Mask" "B.Paste")
			(net "NIC7_MAIN_PWR_BIC_EN")
		)
	)
	(footprint ""
		(layer "B.Cu")
		(at 229.067614 -217.104214 -90)
		(property "Reference" "C3623"
			(at 0 0 90)
			(layer "B.SilkS")
			(hide yes)
			(effects
				(font
					(size 1.27 1.27)
				)
				(justify mirror)
			)
		)
		(property "Value" ""
			(at 0 0 90)
			(layer "B.Fab")
			(effects
				(font
					(size 1.27 1.27)
				)
				(justify mirror)
			)
		)
		(duplicate_pad_numbers_are_jumpers no)
		(fp_line
			(start -0.69215 0.2921)
			(end 0.69215 0.2921)
			(stroke
				(width 0.1524)
				(type default)
			)
			(layer "B.SilkS")
		)
		(fp_line
			(start 0.69215 0.2921)
			(end 0.69215 -0.2921)
			(stroke
				(width 0.1524)
				(type default)
			)
			(layer "B.SilkS")
		)
		(fp_line
			(start -0.69215 -0.2921)
			(end -0.69215 0.2921)
			(stroke
				(width 0.1524)
				(type default)
			)
			(layer "B.SilkS")
		)
		(fp_line
			(start 0.69215 -0.2921)
			(end -0.69215 -0.2921)
			(stroke
				(width 0.1524)
				(type default)
			)
			(layer "B.SilkS")
		)
		(fp_line
			(start -0.51435 0.2794)
			(end 0.51435 0.2794)
			(stroke
				(width 0.1)
				(type default)
			)
			(layer "B.Fab")
		)
		(fp_line
			(start 0.51435 0.2794)
			(end 0.51435 -0.2794)
			(stroke
				(width 0.1)
				(type default)
			)
			(layer "B.Fab")
		)
		(fp_line
			(start -0.51435 -0.2794)
			(end -0.51435 0.2794)
			(stroke
				(width 0.1)
				(type default)
			)
			(layer "B.Fab")
		)
		(fp_line
			(start 0.51435 -0.2794)
			(end -0.51435 -0.2794)
			(stroke
				(width 0.1)
				(type default)
			)
			(layer "B.Fab")
		)
		(pad "1" smd circle
			(at 0.40005 0 90)
			(size 0 0)
			(layers "B.Cu" "B.Mask" "B.Paste")
			(net "P1V2_AUX")
		)
		(pad "2" smd circle
			(at -0.40005 0 90)
			(size 0 0)
			(layers "B.Cu" "B.Mask" "B.Paste")
			(net "GND")
		)
		(zone
			(layer "B.Cu")
			(hatch none 0.5)
			(connect_pads
				(clearance 0)
			)
			(min_thickness 0.25)
			(keepout
				(tracks not_allowed)
				(vias allowed)
				(pads allowed)
				(copperpour not_allowed)
				(footprints allowed)
			)
			(placement
				(enabled no)
				(sheetname "")
			)
			(fill
				(thermal_gap 0.5)
				(thermal_bridge_width 0.5)
				(island_removal_mode 0)
			)
			(polygon
				(pts
					(xy 228.979984 -216.913714) (xy 228.921818 -217.005154) (xy 228.921818 -217.204544) (xy 228.979984 -217.294714)
					(xy 229.155244 -217.294714) (xy 229.213664 -217.204544) (xy 229.213664 -217.005154) (xy 229.155498 -216.913714)
				)
			)
		)
	)
	(footprint ""
		(layer "B.Cu")
		(at 162.4457 -294.4749)
		(property "Reference" "C3218"
			(at 0 0 0)
			(layer "B.SilkS")
			(hide yes)
			(effects
				(font
					(size 1.27 1.27)
				)
				(justify mirror)
			)
		)
		(property "Value" ""
			(at 0 0 0)
			(layer "B.Fab")
			(effects
				(font
					(size 1.27 1.27)
				)
				(justify mirror)
			)
		)
		(duplicate_pad_numbers_are_jumpers no)
		(fp_line
			(start -0.299974 -0.150114)
			(end -0.299974 0.150114)
			(stroke
				(width 0.1)
				(type default)
			)
			(layer "B.Fab")
		)
		(fp_line
			(start -0.299974 0.150114)
			(end 0.299974 0.150114)
			(stroke
				(width 0.1)
				(type default)
			)
			(layer "B.Fab")
		)
		(fp_line
			(start 0.299974 -0.150114)
			(end -0.299974 -0.150114)
			(stroke
				(width 0.1)
				(type default)
			)
			(layer "B.Fab")
		)
		(fp_line
			(start 0.299974 0.150114)
			(end 0.299974 -0.150114)
			(stroke
				(width 0.1)
				(type default)
			)
			(layer "B.Fab")
		)
		(pad "1" smd rect
			(at 0.2667 0 180)
			(size 0.3048 0.381)
			(layers "B.Cu" "B.Mask" "B.Paste")
			(net "PCEPLL4_VDDA18_PEX1")
		)
		(pad "2" smd rect
			(at -0.2667 0 180)
			(size 0.3048 0.381)
			(layers "B.Cu" "B.Mask" "B.Paste")
			(net "GND")
		)
	)
	(footprint ""
		(layer "B.Cu")
		(at 165.774878 -297.79976 90)
		(property "Reference" "C1400"
			(at 0 0 90)
			(layer "B.SilkS")
			(hide yes)
			(effects
				(font
					(size 1.27 1.27)
				)
				(justify mirror)
			)
		)
		(property "Value" ""
			(at 0 0 90)
			(layer "B.Fab")
			(effects
				(font
					(size 1.27 1.27)
				)
				(justify mirror)
			)
		)
		(duplicate_pad_numbers_are_jumpers no)
		(fp_line
			(start 0.299974 -0.150114)
			(end -0.299974 -0.150114)
			(stroke
				(width 0.1)
				(type default)
			)
			(layer "B.Fab")
		)
		(fp_line
			(start -0.299974 -0.150114)
			(end -0.299974 0.150114)
			(stroke
				(width 0.1)
				(type default)
			)
			(layer "B.Fab")
		)
		(fp_line
			(start 0.299974 0.150114)
			(end 0.299974 -0.150114)
			(stroke
				(width 0.1)
				(type default)
			)
			(layer "B.Fab")
		)
		(fp_line
			(start -0.299974 0.150114)
			(end 0.299974 0.150114)
			(stroke
				(width 0.1)
				(type default)
			)
			(layer "B.Fab")
		)
		(pad "1" smd rect
			(at 0.2667 0 270)
			(size 0.3048 0.381)
			(layers "B.Cu" "B.Mask" "B.Paste")
			(net "P0V8_PEX1")
		)
		(pad "2" smd rect
			(at -0.2667 0 270)
			(size 0.3048 0.381)
			(layers "B.Cu" "B.Mask" "B.Paste")
			(net "GND")
		)
	)
	(footprint ""
		(layer "B.Cu")
		(at 67.249802 -288.299906 90)
		(property "Reference" "C2927"
			(at 0 0 90)
			(layer "B.SilkS")
			(hide yes)
			(effects
				(font
					(size 1.27 1.27)
				)
				(justify mirror)
			)
		)
		(property "Value" ""
			(at 0 0 90)
			(layer "B.Fab")
			(effects
				(font
					(size 1.27 1.27)
				)
				(justify mirror)
			)
		)
		(duplicate_pad_numbers_are_jumpers no)
		(fp_line
			(start 0.299974 -0.150114)
			(end -0.299974 -0.150114)
			(stroke
				(width 0.1)
				(type default)
			)
			(layer "B.Fab")
		)
		(fp_line
			(start -0.299974 -0.150114)
			(end -0.299974 0.150114)
			(stroke
				(width 0.1)
				(type default)
			)
			(layer "B.Fab")
		)
		(fp_line
			(start 0.299974 0.150114)
			(end 0.299974 -0.150114)
			(stroke
				(width 0.1)
				(type default)
			)
			(layer "B.Fab")
		)
		(fp_line
			(start -0.299974 0.150114)
			(end 0.299974 0.150114)
			(stroke
				(width 0.1)
				(type default)
			)
			(layer "B.Fab")
		)
		(pad "1" smd rect
			(at 0.2667 0 270)
			(size 0.3048 0.381)
			(layers "B.Cu" "B.Mask" "B.Paste")
			(net "P1V25_PEX0")
		)
		(pad "2" smd rect
			(at -0.2667 0 270)
			(size 0.3048 0.381)
			(layers "B.Cu" "B.Mask" "B.Paste")
			(net "GND")
		)
	)
	(footprint ""
		(layer "B.Cu")
		(at 64.874902 -297.79976 -90)
		(property "Reference" "C1143"
			(at 0 0 90)
			(layer "B.SilkS")
			(hide yes)
			(effects
				(font
					(size 1.27 1.27)
				)
				(justify mirror)
			)
		)
		(property "Value" ""
			(at 0 0 90)
			(layer "B.Fab")
			(effects
				(font
					(size 1.27 1.27)
				)
				(justify mirror)
			)
		)
		(duplicate_pad_numbers_are_jumpers no)
		(fp_line
			(start -0.299974 0.150114)
			(end 0.299974 0.150114)
			(stroke
				(width 0.1)
				(type default)
			)
			(layer "B.Fab")
		)
		(fp_line
			(start 0.299974 0.150114)
			(end 0.299974 -0.150114)
			(stroke
				(width 0.1)
				(type default)
			)
			(layer "B.Fab")
		)
		(fp_line
			(start -0.299974 -0.150114)
			(end -0.299974 0.150114)
			(stroke
				(width 0.1)
				(type default)
			)
			(layer "B.Fab")
		)
		(fp_line
			(start 0.299974 -0.150114)
			(end -0.299974 -0.150114)
			(stroke
				(width 0.1)
				(type default)
			)
			(layer "B.Fab")
		)
		(pad "1" smd rect
			(at 0.2667 0 90)
			(size 0.3048 0.381)
			(layers "B.Cu" "B.Mask" "B.Paste")
			(net "P0V8_PEX0")
		)
		(pad "2" smd rect
			(at -0.2667 0 90)
			(size 0.3048 0.381)
			(layers "B.Cu" "B.Mask" "B.Paste")
			(net "GND")
		)
	)
)
